FILE_TYPE = MULTI_PHYS_TABLE;

PART 'GENOA_SP5'

{========================================================================================}
:VALUE                  | PART_TYPE | MATERIAL | PART_NUMBER    = STANDARD        | LIFECYCLE          | PART_NUMBER   | JEDEC_TYPE               | DESCRIPTION                      | MANUFTR | MANUF_PN    | RD_CMPLS_LVL | CMPLS_LVL | CLASS | DIP_SMD | FROM_PJ        | DATA                | FP_ECN          | EE_CHECK_LIST | CREATOR | CREATEDAY  | PSL | STATUS | ESD_CDM | ESD_HBM | ESD_MM | MSD | PIN_LENGTH_LONG_PIN | PIN_LENGTH_SHORT_PIN ;
{========================================================================================}
 'SOCKET6096_13568-001' | 'SMLF'    | 'IO'     | 'DGA^6000030'(!) = ''               | ''               | 'DGA^6000030' |'SOCKET6096_93-4X120-45XA'| 'SOCKET SP5 6096P LGA(P0.94,H4)' | 'APL'   | '13568-001' | 'EP(V1)'     | ''        | 'IO'  | ''      | 'TITANITE-TOM' | 'APL_13568-001.pdf' | '13568-001.xlsx' | ''            | ''      | '20210715' | ''  | ''     | ''      | ''      | ''     | ''  | '0 MILS'            | '0 MILS'            
 'SOCKET6096_13568-001' | 'SMLF'    | 'EMPTY'  | 'DGA^6000030'(!) = ''               | ''               | 'DGA^6000030' |'SOCKET6096_93-4X120-45XA'| 'SOCKET SP5 6096P LGA(P0.94,H4)' | 'APL'   | '13568-001' | 'EP(V1)'     | ''        | 'IO'  | ''      | 'TITANITE-TOM' | 'APL_13568-001.pdf' | '13568-001.xlsx' | ''            | ''      | '20210715' | ''  | ''     | ''      | ''      | ''     | ''  | '0 MILS'            | '0 MILS'            

END_PART

END.

